(kicad_pcb
	(version 20260206)
	(generator "pcbnew")
	(generator_version "10.0")
	(general
		(thickness 1.6)
		(legacy_teardrops no)
	)
	(paper "A4")
	(title_block
		(title "04192023_DAF0TMB3IC0_F0TG_MB_C_brd_V02_OCP.brd")
		(comment 1 "Grand Teton / footprints 6655-6661 of 8354")
	)
	(layers
		(0 "F.Cu" signal "TOP")
		(4 "In1.Cu" signal "GND")
		(6 "In2.Cu" signal "IN1")
		(8 "In3.Cu" signal "GND1")
		(10 "In4.Cu" signal "IN2")
		(12 "In5.Cu" signal "GND2")
		(14 "In6.Cu" signal "IN3")
		(16 "In7.Cu" signal "GND3")
		(18 "In8.Cu" signal "VCC")
		(20 "In9.Cu" signal "VCC1")
		(22 "In10.Cu" signal "GND4")
		(24 "In11.Cu" signal "IN4")
		(26 "In12.Cu" signal "GND5")
		(28 "In13.Cu" signal "IN5")
		(30 "In14.Cu" signal "GND6")
		(32 "In15.Cu" signal "IN6")
		(34 "In16.Cu" signal "GND7")
		(2 "B.Cu" signal "BOTTOM")
		(9 "F.Adhes" user "F.Adhesive")
		(11 "B.Adhes" user "B.Adhesive")
		(13 "F.Paste" user "Package Geometry/Pastemask Top")
		(15 "B.Paste" user "Package Geometry/Pastemask Bottom")
		(5 "F.SilkS" user "Ref Des/Silkscreen Top")
		(7 "B.SilkS" user "Ref Des/Silkscreen Bottom")
		(1 "F.Mask" user "Board Geometry/Soldermask Top")
		(3 "B.Mask" user "Board Geometry/Soldermask Bottom")
		(17 "Dwgs.User" user "User.Drawings")
		(19 "Cmts.User" user "User.Comments")
		(21 "Eco1.User" user "User.Eco1")
		(23 "Eco2.User" user "User.Eco2")
		(25 "Edge.Cuts" user "Board Geometry/Outline")
		(27 "Margin" user)
		(31 "F.CrtYd" user "Package Geometry/Place Bound Top")
		(29 "B.CrtYd" user "Package Geometry/Place Bound Bottom")
		(35 "F.Fab" user "Ref Des/Assembly Top")
		(33 "B.Fab" user "Ref Des/Assembly Bottom")
	)
	(footprint ""
		(layer "B.Cu")
		(at 143.401542 -81.786222)
		(property "Reference" "R6242"
			(at 0 0 0)
			(layer "B.SilkS")
			(hide yes)
			(effects
				(font
					(size 1.27 1.27)
				)
				(justify mirror)
			)
		)
		(property "Value" ""
			(at 0 0 0)
			(layer "B.Fab")
			(effects
				(font
					(size 1.27 1.27)
				)
				(justify mirror)
			)
		)
		(duplicate_pad_numbers_are_jumpers no)
		(fp_line
			(start -0.7874 -0.4064)
			(end -0.7874 0.4064)
			(stroke
				(width 0.1524)
				(type default)
			)
			(layer "B.SilkS")
		)
		(fp_line
			(start -0.7874 0.4064)
			(end 0.7874 0.4064)
			(stroke
				(width 0.1524)
				(type default)
			)
			(layer "B.SilkS")
		)
		(fp_line
			(start 0.7874 -0.4064)
			(end -0.7874 -0.4064)
			(stroke
				(width 0.1524)
				(type default)
			)
			(layer "B.SilkS")
		)
		(fp_line
			(start 0.7874 0.4064)
			(end 0.7874 -0.4064)
			(stroke
				(width 0.1524)
				(type default)
			)
			(layer "B.SilkS")
		)
		(fp_line
			(start -0.67945 -0.3048)
			(end -0.67945 0.3048)
			(stroke
				(width 0.1)
				(type default)
			)
			(layer "B.Fab")
		)
		(fp_line
			(start -0.67945 0.3048)
			(end -0.120396 0.3048)
			(stroke
				(width 0.1)
				(type default)
			)
			(layer "B.Fab")
		)
		(fp_line
			(start -0.12065 -0.3048)
			(end -0.67945 -0.3048)
			(stroke
				(width 0.1)
				(type default)
			)
			(layer "B.Fab")
		)
		(fp_line
			(start -0.12065 -0.2794)
			(end -0.12065 -0.3048)
			(stroke
				(width 0.1)
				(type default)
			)
			(layer "B.Fab")
		)
		(fp_line
			(start -0.120396 0.2794)
			(end 0.12065 0.2794)
			(stroke
				(width 0.1)
				(type default)
			)
			(layer "B.Fab")
		)
		(fp_line
			(start -0.120396 0.3048)
			(end -0.120396 0.2794)
			(stroke
				(width 0.1)
				(type default)
			)
			(layer "B.Fab")
		)
		(fp_line
			(start 0.12065 -0.305054)
			(end 0.12065 -0.2794)
			(stroke
				(width 0.1)
				(type default)
			)
			(layer "B.Fab")
		)
		(fp_line
			(start 0.12065 -0.2794)
			(end -0.12065 -0.2794)
			(stroke
				(width 0.1)
				(type default)
			)
			(layer "B.Fab")
		)
		(fp_line
			(start 0.12065 0.2794)
			(end 0.12065 0.3048)
			(stroke
				(width 0.1)
				(type default)
			)
			(layer "B.Fab")
		)
		(fp_line
			(start 0.12065 0.3048)
			(end 0.67945 0.3048)
			(stroke
				(width 0.1)
				(type default)
			)
			(layer "B.Fab")
		)
		(fp_line
			(start 0.67945 -0.305054)
			(end 0.12065 -0.305054)
			(stroke
				(width 0.1)
				(type default)
			)
			(layer "B.Fab")
		)
		(fp_line
			(start 0.67945 0.3048)
			(end 0.67945 -0.305054)
			(stroke
				(width 0.1)
				(type default)
			)
			(layer "B.Fab")
		)
		(pad "1" smd circle
			(at 0.40005 0 180)
			(size 0 0)
			(layers "B.Cu" "B.Mask" "B.Paste")
			(net "P3V3_AUX")
		)
		(pad "2" smd circle
			(at -0.40005 0 180)
			(size 0 0)
			(layers "B.Cu" "B.Mask" "B.Paste")
			(net "P1V8_AUX_VCC")
		)
	)
	(footprint ""
		(layer "B.Cu")
		(at 151.010366 -408.517344 90)
		(property "Reference" "C6747"
			(at 0 0 90)
			(layer "B.SilkS")
			(hide yes)
			(effects
				(font
					(size 1.27 1.27)
				)
				(justify mirror)
			)
		)
		(property "Value" ""
			(at 0 0 90)
			(layer "B.Fab")
			(effects
				(font
					(size 1.27 1.27)
				)
				(justify mirror)
			)
		)
		(duplicate_pad_numbers_are_jumpers no)
		(fp_line
			(start 0.299974 -0.150114)
			(end -0.299974 -0.150114)
			(stroke
				(width 0.1)
				(type default)
			)
			(layer "B.Fab")
		)
		(fp_line
			(start -0.299974 -0.150114)
			(end -0.299974 0.150114)
			(stroke
				(width 0.1)
				(type default)
			)
			(layer "B.Fab")
		)
		(fp_line
			(start 0.299974 0.150114)
			(end 0.299974 -0.150114)
			(stroke
				(width 0.1)
				(type default)
			)
			(layer "B.Fab")
		)
		(fp_line
			(start -0.299974 0.150114)
			(end 0.299974 0.150114)
			(stroke
				(width 0.1)
				(type default)
			)
			(layer "B.Fab")
		)
		(pad "1" smd rect
			(at 0.2667 0 270)
			(size 0.3048 0.381)
			(layers "B.Cu" "B.Mask" "B.Paste")
			(net "P5E_CPU1_P3_TX_BUF_C_DP<11>")
		)
		(pad "2" smd rect
			(at -0.2667 0 270)
			(size 0.3048 0.381)
			(layers "B.Cu" "B.Mask" "B.Paste")
			(net "P5E_CPU1_P3_TX_BUF_DP<11>")
		)
	)
	(footprint ""
		(layer "B.Cu")
		(at 149.900386 -313.45505)
		(property "Reference" "R5103"
			(at 0 0 0)
			(layer "B.SilkS")
			(hide yes)
			(effects
				(font
					(size 1.27 1.27)
				)
				(justify mirror)
			)
		)
		(property "Value" ""
			(at 0 0 0)
			(layer "B.Fab")
			(effects
				(font
					(size 1.27 1.27)
				)
				(justify mirror)
			)
		)
		(duplicate_pad_numbers_are_jumpers no)
		(fp_line
			(start -0.7874 -0.4064)
			(end -0.7874 0.4064)
			(stroke
				(width 0.1524)
				(type default)
			)
			(layer "B.SilkS")
		)
		(fp_line
			(start -0.7874 0.4064)
			(end 0.7874 0.4064)
			(stroke
				(width 0.1524)
				(type default)
			)
			(layer "B.SilkS")
		)
		(fp_line
			(start 0.7874 -0.4064)
			(end -0.7874 -0.4064)
			(stroke
				(width 0.1524)
				(type default)
			)
			(layer "B.SilkS")
		)
		(fp_line
			(start 0.7874 0.4064)
			(end 0.7874 -0.4064)
			(stroke
				(width 0.1524)
				(type default)
			)
			(layer "B.SilkS")
		)
		(fp_line
			(start -0.67945 -0.3048)
			(end -0.67945 0.3048)
			(stroke
				(width 0.1)
				(type default)
			)
			(layer "B.Fab")
		)
		(fp_line
			(start -0.67945 0.3048)
			(end -0.120396 0.3048)
			(stroke
				(width 0.1)
				(type default)
			)
			(layer "B.Fab")
		)
		(fp_line
			(start -0.12065 -0.3048)
			(end -0.67945 -0.3048)
			(stroke
				(width 0.1)
				(type default)
			)
			(layer "B.Fab")
		)
		(fp_line
			(start -0.12065 -0.2794)
			(end -0.12065 -0.3048)
			(stroke
				(width 0.1)
				(type default)
			)
			(layer "B.Fab")
		)
		(fp_line
			(start -0.120396 0.2794)
			(end 0.12065 0.2794)
			(stroke
				(width 0.1)
				(type default)
			)
			(layer "B.Fab")
		)
		(fp_line
			(start -0.120396 0.3048)
			(end -0.120396 0.2794)
			(stroke
				(width 0.1)
				(type default)
			)
			(layer "B.Fab")
		)
		(fp_line
			(start 0.12065 -0.305054)
			(end 0.12065 -0.2794)
			(stroke
				(width 0.1)
				(type default)
			)
			(layer "B.Fab")
		)
		(fp_line
			(start 0.12065 -0.2794)
			(end -0.12065 -0.2794)
			(stroke
				(width 0.1)
				(type default)
			)
			(layer "B.Fab")
		)
		(fp_line
			(start 0.12065 0.2794)
			(end 0.12065 0.3048)
			(stroke
				(width 0.1)
				(type default)
			)
			(layer "B.Fab")
		)
		(fp_line
			(start 0.12065 0.3048)
			(end 0.67945 0.3048)
			(stroke
				(width 0.1)
				(type default)
			)
			(layer "B.Fab")
		)
		(fp_line
			(start 0.67945 -0.305054)
			(end 0.12065 -0.305054)
			(stroke
				(width 0.1)
				(type default)
			)
			(layer "B.Fab")
		)
		(fp_line
			(start 0.67945 0.3048)
			(end 0.67945 -0.305054)
			(stroke
				(width 0.1)
				(type default)
			)
			(layer "B.Fab")
		)
		(pad "1" smd circle
			(at 0.40005 0 180)
			(size 0 0)
			(layers "B.Cu" "B.Mask" "B.Paste")
			(net "XTAL_CPU1_X48M_X2")
		)
		(pad "2" smd circle
			(at -0.40005 0 180)
			(size 0 0)
			(layers "B.Cu" "B.Mask" "B.Paste")
			(net "XTAL_CPU1_X48M_X2_R")
		)
	)
	(footprint ""
		(layer "B.Cu")
		(at 142.893542 -384.66268 180)
		(property "Reference" "R881"
			(at 0 0 0)
			(layer "B.SilkS")
			(hide yes)
			(effects
				(font
					(size 1.27 1.27)
				)
				(justify mirror)
			)
		)
		(property "Value" ""
			(at 0 0 0)
			(layer "B.Fab")
			(effects
				(font
					(size 1.27 1.27)
				)
				(justify mirror)
			)
		)
		(duplicate_pad_numbers_are_jumpers no)
		(fp_line
			(start 0.32512 0.175006)
			(end 0.32512 -0.175006)
			(stroke
				(width 0.1)
				(type default)
			)
			(layer "B.Fab")
		)
		(fp_line
			(start 0.32512 -0.175006)
			(end -0.32512 -0.175006)
			(stroke
				(width 0.1)
				(type default)
			)
			(layer "B.Fab")
		)
		(fp_line
			(start -0.32512 0.175006)
			(end 0.32512 0.175006)
			(stroke
				(width 0.1)
				(type default)
			)
			(layer "B.Fab")
		)
		(fp_line
			(start -0.32512 -0.175006)
			(end -0.32512 0.175006)
			(stroke
				(width 0.1)
				(type default)
			)
			(layer "B.Fab")
		)
		(pad "1" smd rect
			(at 0.2667 0)
			(size 0.3048 0.381)
			(layers "B.Cu" "B.Mask" "B.Paste")
			(net "TEST1_RT_CPU1_P2")
		)
		(pad "2" smd rect
			(at -0.2667 0 180)
			(size 0.3048 0.381)
			(layers "B.Cu" "B.Mask" "B.Paste")
			(net "GND")
		)
	)
	(footprint ""
		(layer "B.Cu")
		(at 366.566958 -272.284952 180)
		(property "Reference" "C2213"
			(at 0 0 0)
			(layer "B.SilkS")
			(hide yes)
			(effects
				(font
					(size 1.27 1.27)
				)
				(justify mirror)
			)
		)
		(property "Value" ""
			(at 0 0 0)
			(layer "B.Fab")
			(effects
				(font
					(size 1.27 1.27)
				)
				(justify mirror)
			)
		)
		(duplicate_pad_numbers_are_jumpers no)
		(fp_line
			(start 0.7874 0.4064)
			(end 0.7874 -0.4064)
			(stroke
				(width 0.1524)
				(type default)
			)
			(layer "B.SilkS")
		)
		(fp_line
			(start 0.7874 -0.4064)
			(end -0.7874 -0.4064)
			(stroke
				(width 0.1524)
				(type default)
			)
			(layer "B.SilkS")
		)
		(fp_line
			(start -0.7874 0.4064)
			(end 0.7874 0.4064)
			(stroke
				(width 0.1524)
				(type default)
			)
			(layer "B.SilkS")
		)
		(fp_line
			(start -0.7874 -0.4064)
			(end -0.7874 0.4064)
			(stroke
				(width 0.1524)
				(type default)
			)
			(layer "B.SilkS")
		)
		(fp_line
			(start 0.67945 0.3048)
			(end 0.67945 -0.305054)
			(stroke
				(width 0.1)
				(type default)
			)
			(layer "B.Fab")
		)
		(fp_line
			(start 0.67945 -0.305054)
			(end 0.12065 -0.305054)
			(stroke
				(width 0.1)
				(type default)
			)
			(layer "B.Fab")
		)
		(fp_line
			(start 0.12065 0.3048)
			(end 0.67945 0.3048)
			(stroke
				(width 0.1)
				(type default)
			)
			(layer "B.Fab")
		)
		(fp_line
			(start 0.12065 0.2794)
			(end 0.12065 0.3048)
			(stroke
				(width 0.1)
				(type default)
			)
			(layer "B.Fab")
		)
		(fp_line
			(start 0.12065 -0.2794)
			(end -0.12065 -0.2794)
			(stroke
				(width 0.1)
				(type default)
			)
			(layer "B.Fab")
		)
		(fp_line
			(start 0.12065 -0.305054)
			(end 0.12065 -0.2794)
			(stroke
				(width 0.1)
				(type default)
			)
			(layer "B.Fab")
		)
		(fp_line
			(start -0.120396 0.3048)
			(end -0.120396 0.2794)
			(stroke
				(width 0.1)
				(type default)
			)
			(layer "B.Fab")
		)
		(fp_line
			(start -0.120396 0.2794)
			(end 0.12065 0.2794)
			(stroke
				(width 0.1)
				(type default)
			)
			(layer "B.Fab")
		)
		(fp_line
			(start -0.12065 -0.2794)
			(end -0.12065 -0.3048)
			(stroke
				(width 0.1)
				(type default)
			)
			(layer "B.Fab")
		)
		(fp_line
			(start -0.12065 -0.3048)
			(end -0.67945 -0.3048)
			(stroke
				(width 0.1)
				(type default)
			)
			(layer "B.Fab")
		)
		(fp_line
			(start -0.67945 0.3048)
			(end -0.120396 0.3048)
			(stroke
				(width 0.1)
				(type default)
			)
			(layer "B.Fab")
		)
		(fp_line
			(start -0.67945 -0.3048)
			(end -0.67945 0.3048)
			(stroke
				(width 0.1)
				(type default)
			)
			(layer "B.Fab")
		)
		(pad "1" smd circle
			(at 0.40005 0)
			(size 0 0)
			(layers "B.Cu" "B.Mask" "B.Paste")
			(net "PVDDCR_CPU1_P0")
		)
		(pad "2" smd circle
			(at -0.40005 0)
			(size 0 0)
			(layers "B.Cu" "B.Mask" "B.Paste")
			(net "GND")
		)
	)
	(footprint ""
		(layer "B.Cu")
		(at 45.928788 -381.6223)
		(property "Reference" "C7022"
			(at 0 0 0)
			(layer "B.SilkS")
			(hide yes)
			(effects
				(font
					(size 1.27 1.27)
				)
				(justify mirror)
			)
		)
		(property "Value" ""
			(at 0 0 0)
			(layer "B.Fab")
			(effects
				(font
					(size 1.27 1.27)
				)
				(justify mirror)
			)
		)
		(duplicate_pad_numbers_are_jumpers no)
		(fp_line
			(start -1.524 -0.762)
			(end -1.524 0.762)
			(stroke
				(width 0.1524)
				(type default)
			)
			(layer "B.SilkS")
		)
		(fp_line
			(start -1.524 0.762)
			(end 1.524 0.762)
			(stroke
				(width 0.1524)
				(type default)
			)
			(layer "B.SilkS")
		)
		(fp_line
			(start 1.524 -0.762)
			(end -1.524 -0.762)
			(stroke
				(width 0.1524)
				(type default)
			)
			(layer "B.SilkS")
		)
		(fp_line
			(start 1.524 0.762)
			(end 1.524 -0.762)
			(stroke
				(width 0.1524)
				(type default)
			)
			(layer "B.SilkS")
		)
		(fp_line
			(start -1.1049 -0.724916)
			(end 1.1049 -0.724916)
			(stroke
				(width 0.1)
				(type default)
			)
			(layer "B.Fab")
		)
		(fp_line
			(start -1.1049 0.724916)
			(end -1.1049 -0.724916)
			(stroke
				(width 0.1)
				(type default)
			)
			(layer "B.Fab")
		)
		(fp_line
			(start 1.1049 -0.724916)
			(end 1.1049 0.724916)
			(stroke
				(width 0.1)
				(type default)
			)
			(layer "B.Fab")
		)
		(fp_line
			(start 1.1049 0.724916)
			(end -1.1049 0.724916)
			(stroke
				(width 0.1)
				(type default)
			)
			(layer "B.Fab")
		)
		(pad "1" smd rect
			(at 0.889 0)
			(size 1.016 1.27)
			(layers "B.Cu" "B.Mask" "B.Paste")
			(net "P0V9_CPU1_RT0_2A")
		)
		(pad "2" smd rect
			(at -0.889 0)
			(size 1.016 1.27)
			(layers "B.Cu" "B.Mask" "B.Paste")
			(net "GND")
		)
	)
	(footprint ""
		(layer "B.Cu")
		(at 194.094608 -126.833376 -90)
		(property "Reference" "R186"
			(at 0 0 90)
			(layer "B.SilkS")
			(hide yes)
			(effects
				(font
					(size 1.27 1.27)
				)
				(justify mirror)
			)
		)
		(property "Value" ""
			(at 0 0 90)
			(layer "B.Fab")
			(effects
				(font
					(size 1.27 1.27)
				)
				(justify mirror)
			)
		)
		(duplicate_pad_numbers_are_jumpers no)
		(fp_line
			(start -0.7874 0.4064)
			(end 0.7874 0.4064)
			(stroke
				(width 0.1524)
				(type default)
			)
			(layer "B.SilkS")
		)
		(fp_line
			(start 0.7874 0.4064)
			(end 0.7874 -0.4064)
			(stroke
				(width 0.1524)
				(type default)
			)
			(layer "B.SilkS")
		)
		(fp_line
			(start -0.7874 -0.4064)
			(end -0.7874 0.4064)
			(stroke
				(width 0.1524)
				(type default)
			)
			(layer "B.SilkS")
		)
		(fp_line
			(start 0.7874 -0.4064)
			(end -0.7874 -0.4064)
			(stroke
				(width 0.1524)
				(type default)
			)
			(layer "B.SilkS")
		)
		(fp_line
			(start -0.67945 0.3048)
			(end -0.120396 0.3048)
			(stroke
				(width 0.1)
				(type default)
			)
			(layer "B.Fab")
		)
		(fp_line
			(start -0.120396 0.3048)
			(end -0.120396 0.2794)
			(stroke
				(width 0.1)
				(type default)
			)
			(layer "B.Fab")
		)
		(fp_line
			(start 0.12065 0.3048)
			(end 0.67945 0.3048)
			(stroke
				(width 0.1)
				(type default)
			)
			(layer "B.Fab")
		)
		(fp_line
			(start 0.67945 0.3048)
			(end 0.67945 -0.305054)
			(stroke
				(width 0.1)
				(type default)
			)
			(layer "B.Fab")
		)
		(fp_line
			(start -0.120396 0.2794)
			(end 0.12065 0.2794)
			(stroke
				(width 0.1)
				(type default)
			)
			(layer "B.Fab")
		)
		(fp_line
			(start 0.12065 0.2794)
			(end 0.12065 0.3048)
			(stroke
				(width 0.1)
				(type default)
			)
			(layer "B.Fab")
		)
		(fp_line
			(start -0.12065 -0.2794)
			(end -0.12065 -0.3048)
			(stroke
				(width 0.1)
				(type default)
			)
			(layer "B.Fab")
		)
		(fp_line
			(start 0.12065 -0.2794)
			(end -0.12065 -0.2794)
			(stroke
				(width 0.1)
				(type default)
			)
			(layer "B.Fab")
		)
		(fp_line
			(start -0.67945 -0.3048)
			(end -0.67945 0.3048)
			(stroke
				(width 0.1)
				(type default)
			)
			(layer "B.Fab")
		)
		(fp_line
			(start -0.12065 -0.3048)
			(end -0.67945 -0.3048)
			(stroke
				(width 0.1)
				(type default)
			)
			(layer "B.Fab")
		)
		(fp_line
			(start 0.12065 -0.305054)
			(end 0.12065 -0.2794)
			(stroke
				(width 0.1)
				(type default)
			)
			(layer "B.Fab")
		)
		(fp_line
			(start 0.67945 -0.305054)
			(end 0.12065 -0.305054)
			(stroke
				(width 0.1)
				(type default)
			)
			(layer "B.Fab")
		)
		(pad "1" smd circle
			(at 0.40005 0 90)
			(size 0 0)
			(layers "B.Cu" "B.Mask" "B.Paste")
			(net "FM_CPU0_FORCE_SELFREFRESH")
		)
		(pad "2" smd circle
			(at -0.40005 0 90)
			(size 0 0)
			(layers "B.Cu" "B.Mask" "B.Paste")
			(net "CPU0_FORCE_SELFREFRESH")
		)
	)
)
